(kicad_pcb
	(version 20260206)
	(generator "pcbnew")
	(generator_version "10.0")
	(general
		(thickness 1.6)
		(legacy_teardrops no)
	)
	(paper "A4")
	(title_block
		(title "01162023_DA0F0TEBIF0_F0T_Expander_BD_F_brd_V02_OCP.brd")
		(comment 1 "Grand Teton / footprint 4451 of 9728 (PEX3), pads 234-355 of 2397")
	)
	(layers
		(0 "F.Cu" signal "TOP")
		(4 "In1.Cu" signal "GND")
		(6 "In2.Cu" signal "VCC")
		(8 "In3.Cu" signal "VCC1")
		(10 "In4.Cu" signal "GND1")
		(12 "In5.Cu" signal "IN1")
		(14 "In6.Cu" signal "GND2")
		(16 "In7.Cu" signal "IN2")
		(18 "In8.Cu" signal "GND3")
		(20 "In9.Cu" signal "IN3")
		(22 "In10.Cu" signal "GND4")
		(24 "In11.Cu" signal "IN4")
		(26 "In12.Cu" signal "GND5")
		(28 "In13.Cu" signal "IN5")
		(30 "In14.Cu" signal "GND6")
		(32 "In15.Cu" signal "IN6")
		(34 "In16.Cu" signal "GND7")
		(2 "B.Cu" signal "BOTTOM")
		(9 "F.Adhes" user "F.Adhesive")
		(11 "B.Adhes" user "B.Adhesive")
		(13 "F.Paste" user "Package Geometry/Pastemask Top")
		(15 "B.Paste" user "Package Geometry/Pastemask Bottom")
		(5 "F.SilkS" user "Ref Des/Silkscreen Top")
		(7 "B.SilkS" user "Ref Des/Silkscreen Bottom")
		(1 "F.Mask" user "Board Geometry/Soldermask Top")
		(3 "B.Mask" user "Board Geometry/Soldermask Bottom")
		(17 "Dwgs.User" user "User.Drawings")
		(19 "Cmts.User" user "User.Comments")
		(21 "Eco1.User" user "User.Eco1")
		(23 "Eco2.User" user "User.Eco2")
		(25 "Edge.Cuts" user "Board Geometry/Outline")
		(27 "Margin" user)
		(31 "F.CrtYd" user "Package Geometry/Place Bound Top")
		(29 "B.CrtYd" user "Package Geometry/Place Bound Bottom")
		(35 "F.Fab" user "Ref Des/Assembly Top")
		(33 "B.Fab" user "Ref Des/Assembly Bottom")
	)
	(footprint ""
		(layer "F.Cu")
		(at 407.949908 -295.89984)
		(property "Reference" "PEX3"
			(at -3.358642 35.5727 0)
			(unlocked yes)
			(layer "F.SilkS")
			(effects
				(font
					(size 2.032 1.524)
					(thickness 0.1524)
				)
				(justify left)
			)
		)
		(property "Value" ""
			(at 0 0 0)
			(layer "F.Fab")
			(effects
				(font
					(size 1.27 1.27)
				)
			)
		)
		(duplicate_pad_numbers_are_jumpers no)
		(pad "AD40" smd circle
			(at 14.249908 -0.94996)
			(size 0.4572 0.4572)
			(layers "F.Cu" "F.Mask" "F.Paste")
			(net "GND")
		)
		(pad "AD41" smd circle
			(at 15.200122 -0.94996)
			(size 0.4572 0.4572)
			(layers "F.Cu" "F.Mask" "F.Paste")
			(net "Net_1558")
		)
		(pad "AD42" smd circle
			(at 16.150082 -0.94996)
			(size 0.4572 0.4572)
			(layers "F.Cu" "F.Mask" "F.Paste")
			(net "Net_1547")
		)
		(pad "AD43" smd circle
			(at 17.100042 -0.94996)
			(size 0.4572 0.4572)
			(layers "F.Cu" "F.Mask" "F.Paste")
			(net "GND")
		)
		(pad "AD44" smd circle
			(at 18.050002 -0.94996)
			(size 0.4572 0.4572)
			(layers "F.Cu" "F.Mask" "F.Paste")
			(net "GND")
		)
		(pad "AD45" smd circle
			(at 18.999962 -0.94996)
			(size 0.4572 0.4572)
			(layers "F.Cu" "F.Mask" "F.Paste")
			(net "GND")
		)
		(pad "AD46" smd circle
			(at 19.949922 -0.94996)
			(size 0.4572 0.4572)
			(layers "F.Cu" "F.Mask" "F.Paste")
			(net "GND")
		)
		(pad "AD47" smd circle
			(at 20.899882 -0.94996)
			(size 0.4572 0.4572)
			(layers "F.Cu" "F.Mask" "F.Paste")
			(net "GND")
		)
		(pad "AD48" smd circle
			(at 21.850096 -0.94996)
			(size 0.4572 0.4572)
			(layers "F.Cu" "F.Mask" "F.Paste")
			(net "Net_1488")
		)
		(pad "AD49" smd circle
			(at 22.800056 -0.94996)
			(size 0.4572 0.4572)
			(layers "F.Cu" "F.Mask" "F.Paste")
			(net "Net_1478")
		)
		(pad "AE1" smd circle
			(at -22.800056 0)
			(size 0.4572 0.4572)
			(layers "F.Cu" "F.Mask" "F.Paste")
			(net "CLK_100M_DB800ZL_PEX3_S3_R_DN")
		)
		(pad "AE2" smd circle
			(at -21.850096 0)
			(size 0.4572 0.4572)
			(layers "F.Cu" "F.Mask" "F.Paste")
			(net "CLK_100M_DB800ZL_PEX3_S3_R_DP")
		)
		(pad "AE3" smd circle
			(at -20.899882 0)
			(size 0.4572 0.4572)
			(layers "F.Cu" "F.Mask" "F.Paste")
			(net "GND")
		)
		(pad "AE4" smd circle
			(at -19.949922 0)
			(size 0.4572 0.4572)
			(layers "F.Cu" "F.Mask" "F.Paste")
			(net "GND")
		)
		(pad "AE5" smd circle
			(at -18.999962 0)
			(size 0.4572 0.4572)
			(layers "F.Cu" "F.Mask" "F.Paste")
			(net "GND")
		)
		(pad "AE6" smd circle
			(at -18.050002 0)
			(size 0.4572 0.4572)
			(layers "F.Cu" "F.Mask" "F.Paste")
			(net "GND")
		)
		(pad "AE7" smd circle
			(at -17.100042 0)
			(size 0.4572 0.4572)
			(layers "F.Cu" "F.Mask" "F.Paste")
			(net "Net_5484")
		)
		(pad "AE8" smd circle
			(at -16.150082 0)
			(size 0.4572 0.4572)
			(layers "F.Cu" "F.Mask" "F.Paste")
			(net "Net_5491")
		)
		(pad "AE9" smd circle
			(at -15.200122 0)
			(size 0.4572 0.4572)
			(layers "F.Cu" "F.Mask" "F.Paste")
			(net "GND")
		)
		(pad "AE10" smd circle
			(at -14.249908 0)
			(size 0.4572 0.4572)
			(layers "F.Cu" "F.Mask" "F.Paste")
			(net "P1V8_PEX")
		)
		(pad "AE11" smd circle
			(at -13.299948 0)
			(size 0.4572 0.4572)
			(layers "F.Cu" "F.Mask" "F.Paste")
			(net "GND")
		)
		(pad "AE12" smd circle
			(at -12.349988 0)
			(size 0.4572 0.4572)
			(layers "F.Cu" "F.Mask" "F.Paste")
			(net "GND")
		)
		(pad "AE13" smd circle
			(at -11.400028 0)
			(size 0.4572 0.4572)
			(layers "F.Cu" "F.Mask" "F.Paste")
			(net "PCEPLL3_VDDA18_PEX3")
		)
		(pad "AE14" smd circle
			(at -10.450068 0)
			(size 0.4572 0.4572)
			(layers "F.Cu" "F.Mask" "F.Paste")
			(net "GND")
		)
		(pad "AE15" smd circle
			(at -9.500108 0)
			(size 0.4572 0.4572)
			(layers "F.Cu" "F.Mask" "F.Paste")
			(net "P0V8_PEX3")
		)
		(pad "AE16" smd circle
			(at -8.549894 0)
			(size 0.4572 0.4572)
			(layers "F.Cu" "F.Mask" "F.Paste")
			(net "GND")
		)
		(pad "AE17" smd circle
			(at -7.599934 0)
			(size 0.4572 0.4572)
			(layers "F.Cu" "F.Mask" "F.Paste")
			(net "P0V8_PEX3")
		)
		(pad "AE18" smd circle
			(at -6.649974 0)
			(size 0.4572 0.4572)
			(layers "F.Cu" "F.Mask" "F.Paste")
			(net "GND")
		)
		(pad "AE19" smd circle
			(at -5.700014 0)
			(size 0.4572 0.4572)
			(layers "F.Cu" "F.Mask" "F.Paste")
			(net "P0V8_PEX3")
		)
		(pad "AE20" smd circle
			(at -4.750054 0)
			(size 0.4572 0.4572)
			(layers "F.Cu" "F.Mask" "F.Paste")
			(net "GND")
		)
		(pad "AE21" smd circle
			(at -3.800094 0)
			(size 0.4572 0.4572)
			(layers "F.Cu" "F.Mask" "F.Paste")
			(net "P0V8_PEX3")
		)
		(pad "AE22" smd circle
			(at -2.84988 0)
			(size 0.4572 0.4572)
			(layers "F.Cu" "F.Mask" "F.Paste")
			(net "GND")
		)
		(pad "AE23" smd circle
			(at -1.89992 0)
			(size 0.4572 0.4572)
			(layers "F.Cu" "F.Mask" "F.Paste")
			(net "P0V8_PEX3")
		)
		(pad "AE24" smd circle
			(at -0.94996 0)
			(size 0.4572 0.4572)
			(layers "F.Cu" "F.Mask" "F.Paste")
			(net "GND")
		)
		(pad "AE25" smd circle
			(at 0 0)
			(size 0.4572 0.4572)
			(layers "F.Cu" "F.Mask" "F.Paste")
			(net "P0V8_PEX3")
		)
		(pad "AE26" smd circle
			(at 0.94996 0)
			(size 0.4572 0.4572)
			(layers "F.Cu" "F.Mask" "F.Paste")
			(net "GND")
		)
		(pad "AE27" smd circle
			(at 1.89992 0)
			(size 0.4572 0.4572)
			(layers "F.Cu" "F.Mask" "F.Paste")
			(net "P0V8_PEX3")
		)
		(pad "AE28" smd circle
			(at 2.84988 0)
			(size 0.4572 0.4572)
			(layers "F.Cu" "F.Mask" "F.Paste")
			(net "GND")
		)
		(pad "AE29" smd circle
			(at 3.800094 0)
			(size 0.4572 0.4572)
			(layers "F.Cu" "F.Mask" "F.Paste")
			(net "P0V8_PEX3")
		)
		(pad "AE30" smd circle
			(at 4.750054 0)
			(size 0.4572 0.4572)
			(layers "F.Cu" "F.Mask" "F.Paste")
			(net "GND")
		)
		(pad "AE31" smd circle
			(at 5.700014 0)
			(size 0.4572 0.4572)
			(layers "F.Cu" "F.Mask" "F.Paste")
			(net "P0V8_PEX3")
		)
		(pad "AE32" smd circle
			(at 6.649974 0)
			(size 0.4572 0.4572)
			(layers "F.Cu" "F.Mask" "F.Paste")
			(net "GND")
		)
		(pad "AE33" smd circle
			(at 7.599934 0)
			(size 0.4572 0.4572)
			(layers "F.Cu" "F.Mask" "F.Paste")
			(net "P0V8_SERDES_VDDA_PEX3")
		)
		(pad "AE34" smd circle
			(at 8.549894 0)
			(size 0.4572 0.4572)
			(layers "F.Cu" "F.Mask" "F.Paste")
			(net "P0V8_SERDES_VDDA_PEX3")
		)
		(pad "AE35" smd circle
			(at 9.500108 0)
			(size 0.4572 0.4572)
			(layers "F.Cu" "F.Mask" "F.Paste")
			(net "GND")
		)
		(pad "AE36" smd circle
			(at 10.450068 0)
			(size 0.4572 0.4572)
			(layers "F.Cu" "F.Mask" "F.Paste")
			(net "P1V25_PEX3")
		)
		(pad "AE37" smd circle
			(at 11.400028 0)
			(size 0.4572 0.4572)
			(layers "F.Cu" "F.Mask" "F.Paste")
			(net "GND")
		)
		(pad "AE38" smd circle
			(at 12.349988 0)
			(size 0.4572 0.4572)
			(layers "F.Cu" "F.Mask" "F.Paste")
			(net "P1V25_SERDES_VDDPLL_PEX3")
		)
		(pad "AE39" smd circle
			(at 13.299948 0)
			(size 0.4572 0.4572)
			(layers "F.Cu" "F.Mask" "F.Paste")
			(net "GND")
		)
		(pad "AE40" smd circle
			(at 14.249908 0)
			(size 0.4572 0.4572)
			(layers "F.Cu" "F.Mask" "F.Paste")
			(net "GND")
		)
		(pad "AE41" smd circle
			(at 15.200122 0)
			(size 0.4572 0.4572)
			(layers "F.Cu" "F.Mask" "F.Paste")
			(net "GND")
		)
		(pad "AE42" smd circle
			(at 16.150082 0)
			(size 0.4572 0.4572)
			(layers "F.Cu" "F.Mask" "F.Paste")
			(net "GND")
		)
		(pad "AE43" smd circle
			(at 17.100042 0)
			(size 0.4572 0.4572)
			(layers "F.Cu" "F.Mask" "F.Paste")
			(net "Net_1540")
		)
		(pad "AE44" smd circle
			(at 18.050002 0)
			(size 0.4572 0.4572)
			(layers "F.Cu" "F.Mask" "F.Paste")
			(net "Net_1526")
		)
		(pad "AE45" smd circle
			(at 18.999962 0)
			(size 0.4572 0.4572)
			(layers "F.Cu" "F.Mask" "F.Paste")
			(net "GND")
		)
		(pad "AE46" smd circle
			(at 19.949922 0)
			(size 0.4572 0.4572)
			(layers "F.Cu" "F.Mask" "F.Paste")
			(net "Net_1419")
		)
		(pad "AE47" smd circle
			(at 20.899882 0)
			(size 0.4572 0.4572)
			(layers "F.Cu" "F.Mask" "F.Paste")
			(net "Net_1453")
		)
		(pad "AE48" smd circle
			(at 21.850096 0)
			(size 0.4572 0.4572)
			(layers "F.Cu" "F.Mask" "F.Paste")
			(net "GND")
		)
		(pad "AE49" smd circle
			(at 22.800056 0)
			(size 0.4572 0.4572)
			(layers "F.Cu" "F.Mask" "F.Paste")
			(net "GND")
		)
		(pad "AF1" smd circle
			(at -22.800056 0.94996)
			(size 0.4572 0.4572)
			(layers "F.Cu" "F.Mask" "F.Paste")
			(net "GND")
		)
		(pad "AF2" smd circle
			(at -21.850096 0.94996)
			(size 0.4572 0.4572)
			(layers "F.Cu" "F.Mask" "F.Paste")
			(net "GND")
		)
		(pad "AF3" smd circle
			(at -20.899882 0.94996)
			(size 0.4572 0.4572)
			(layers "F.Cu" "F.Mask" "F.Paste")
			(net "GND")
		)
		(pad "AF4" smd circle
			(at -19.949922 0.94996)
			(size 0.4572 0.4572)
			(layers "F.Cu" "F.Mask" "F.Paste")
			(net "Net_5403")
		)
		(pad "AF5" smd circle
			(at -18.999962 0.94996)
			(size 0.4572 0.4572)
			(layers "F.Cu" "F.Mask" "F.Paste")
			(net "Net_5404")
		)
		(pad "AF6" smd circle
			(at -18.050002 0.94996)
			(size 0.4572 0.4572)
			(layers "F.Cu" "F.Mask" "F.Paste")
			(net "GND")
		)
		(pad "AF7" smd circle
			(at -17.100042 0.94996)
			(size 0.4572 0.4572)
			(layers "F.Cu" "F.Mask" "F.Paste")
			(net "SPI_PEX3_SDIO0")
		)
		(pad "AF8" smd circle
			(at -16.150082 0.94996)
			(size 0.4572 0.4572)
			(layers "F.Cu" "F.Mask" "F.Paste")
			(net "SPI_PEX3_SDIO1")
		)
		(pad "AF9" smd circle
			(at -15.200122 0.94996)
			(size 0.4572 0.4572)
			(layers "F.Cu" "F.Mask" "F.Paste")
			(net "GND")
		)
		(pad "AF10" smd circle
			(at -14.249908 0.94996)
			(size 0.4572 0.4572)
			(layers "F.Cu" "F.Mask" "F.Paste")
			(net "P1V8_PEX")
		)
		(pad "AF11" smd circle
			(at -13.299948 0.94996)
			(size 0.4572 0.4572)
			(layers "F.Cu" "F.Mask" "F.Paste")
			(net "GND")
		)
		(pad "AF12" smd circle
			(at -12.349988 0.94996)
			(size 0.4572 0.4572)
			(layers "F.Cu" "F.Mask" "F.Paste")
			(net "PCEPLL4_VDDA18_PEX3")
		)
		(pad "AF13" smd circle
			(at -11.400028 0.94996)
			(size 0.4572 0.4572)
			(layers "F.Cu" "F.Mask" "F.Paste")
			(net "GND")
		)
		(pad "AF14" smd circle
			(at -10.450068 0.94996)
			(size 0.4572 0.4572)
			(layers "F.Cu" "F.Mask" "F.Paste")
			(net "P0V8_PEX3")
		)
		(pad "AF15" smd circle
			(at -9.500108 0.94996)
			(size 0.4572 0.4572)
			(layers "F.Cu" "F.Mask" "F.Paste")
			(net "GND")
		)
		(pad "AF16" smd circle
			(at -8.549894 0.94996)
			(size 0.4572 0.4572)
			(layers "F.Cu" "F.Mask" "F.Paste")
			(net "P0V8_PEX3")
		)
		(pad "AF17" smd circle
			(at -7.599934 0.94996)
			(size 0.4572 0.4572)
			(layers "F.Cu" "F.Mask" "F.Paste")
			(net "GND")
		)
		(pad "AF18" smd circle
			(at -6.649974 0.94996)
			(size 0.4572 0.4572)
			(layers "F.Cu" "F.Mask" "F.Paste")
			(net "P0V8_PEX3")
		)
		(pad "AF19" smd circle
			(at -5.700014 0.94996)
			(size 0.4572 0.4572)
			(layers "F.Cu" "F.Mask" "F.Paste")
			(net "GND")
		)
		(pad "AF20" smd circle
			(at -4.750054 0.94996)
			(size 0.4572 0.4572)
			(layers "F.Cu" "F.Mask" "F.Paste")
			(net "P0V8_PEX3")
		)
		(pad "AF21" smd circle
			(at -3.800094 0.94996)
			(size 0.4572 0.4572)
			(layers "F.Cu" "F.Mask" "F.Paste")
			(net "GND")
		)
		(pad "AF22" smd circle
			(at -2.84988 0.94996)
			(size 0.4572 0.4572)
			(layers "F.Cu" "F.Mask" "F.Paste")
			(net "P0V8_PEX3")
		)
		(pad "AF23" smd circle
			(at -1.89992 0.94996)
			(size 0.4572 0.4572)
			(layers "F.Cu" "F.Mask" "F.Paste")
			(net "GND")
		)
		(pad "AF24" smd circle
			(at -0.94996 0.94996)
			(size 0.4572 0.4572)
			(layers "F.Cu" "F.Mask" "F.Paste")
			(net "P0V8_PEX3")
		)
		(pad "AF25" smd circle
			(at 0 0.94996)
			(size 0.4572 0.4572)
			(layers "F.Cu" "F.Mask" "F.Paste")
			(net "GND")
		)
		(pad "AF26" smd circle
			(at 0.94996 0.94996)
			(size 0.4572 0.4572)
			(layers "F.Cu" "F.Mask" "F.Paste")
			(net "P0V8_PEX3")
		)
		(pad "AF27" smd circle
			(at 1.89992 0.94996)
			(size 0.4572 0.4572)
			(layers "F.Cu" "F.Mask" "F.Paste")
			(net "GND")
		)
		(pad "AF28" smd circle
			(at 2.84988 0.94996)
			(size 0.4572 0.4572)
			(layers "F.Cu" "F.Mask" "F.Paste")
			(net "P0V8_PEX3")
		)
		(pad "AF29" smd circle
			(at 3.800094 0.94996)
			(size 0.4572 0.4572)
			(layers "F.Cu" "F.Mask" "F.Paste")
			(net "GND")
		)
		(pad "AF30" smd circle
			(at 4.750054 0.94996)
			(size 0.4572 0.4572)
			(layers "F.Cu" "F.Mask" "F.Paste")
			(net "P0V8_PEX3")
		)
		(pad "AF31" smd circle
			(at 5.700014 0.94996)
			(size 0.4572 0.4572)
			(layers "F.Cu" "F.Mask" "F.Paste")
			(net "GND")
		)
		(pad "AF32" smd circle
			(at 6.649974 0.94996)
			(size 0.4572 0.4572)
			(layers "F.Cu" "F.Mask" "F.Paste")
			(net "P0V8_SERDES_VDDA_PEX3")
		)
		(pad "AF33" smd circle
			(at 7.599934 0.94996)
			(size 0.4572 0.4572)
			(layers "F.Cu" "F.Mask" "F.Paste")
			(net "P0V8_SERDES_VDDA_PEX3")
		)
		(pad "AF34" smd circle
			(at 8.549894 0.94996)
			(size 0.4572 0.4572)
			(layers "F.Cu" "F.Mask" "F.Paste")
			(net "P0V8_SERDES_VDDA_PEX3")
		)
		(pad "AF35" smd circle
			(at 9.500108 0.94996)
			(size 0.4572 0.4572)
			(layers "F.Cu" "F.Mask" "F.Paste")
			(net "GND")
		)
		(pad "AF36" smd circle
			(at 10.450068 0.94996)
			(size 0.4572 0.4572)
			(layers "F.Cu" "F.Mask" "F.Paste")
			(net "P1V25_PEX3")
		)
		(pad "AF37" smd circle
			(at 11.400028 0.94996)
			(size 0.4572 0.4572)
			(layers "F.Cu" "F.Mask" "F.Paste")
			(net "GND")
		)
		(pad "AF38" smd circle
			(at 12.349988 0.94996)
			(size 0.4572 0.4572)
			(layers "F.Cu" "F.Mask" "F.Paste")
			(net "P1V25_SERDES_VDDPLL_PEX3")
		)
		(pad "AF39" smd circle
			(at 13.299948 0.94996)
			(size 0.4572 0.4572)
			(layers "F.Cu" "F.Mask" "F.Paste")
			(net "GND")
		)
		(pad "AF40" smd circle
			(at 14.249908 0.94996)
			(size 0.4572 0.4572)
			(layers "F.Cu" "F.Mask" "F.Paste")
			(net "GND")
		)
		(pad "AF41" smd circle
			(at 15.200122 0.94996)
			(size 0.4572 0.4572)
			(layers "F.Cu" "F.Mask" "F.Paste")
			(net "Net_1530")
		)
		(pad "AF42" smd circle
			(at 16.150082 0.94996)
			(size 0.4572 0.4572)
			(layers "F.Cu" "F.Mask" "F.Paste")
			(net "Net_1519")
		)
		(pad "AF43" smd circle
			(at 17.100042 0.94996)
			(size 0.4572 0.4572)
			(layers "F.Cu" "F.Mask" "F.Paste")
			(net "GND")
		)
		(pad "AF44" smd circle
			(at 18.050002 0.94996)
			(size 0.4572 0.4572)
			(layers "F.Cu" "F.Mask" "F.Paste")
			(net "GND")
		)
		(pad "AF45" smd circle
			(at 18.999962 0.94996)
			(size 0.4572 0.4572)
			(layers "F.Cu" "F.Mask" "F.Paste")
			(net "GND")
		)
		(pad "AF46" smd circle
			(at 19.949922 0.94996)
			(size 0.4572 0.4572)
			(layers "F.Cu" "F.Mask" "F.Paste")
			(net "GND")
		)
		(pad "AF47" smd circle
			(at 20.899882 0.94996)
			(size 0.4572 0.4572)
			(layers "F.Cu" "F.Mask" "F.Paste")
			(net "GND")
		)
		(pad "AF48" smd circle
			(at 21.850096 0.94996)
			(size 0.4572 0.4572)
			(layers "F.Cu" "F.Mask" "F.Paste")
			(net "Net_1447")
		)
		(pad "AF49" smd circle
			(at 22.800056 0.94996)
			(size 0.4572 0.4572)
			(layers "F.Cu" "F.Mask" "F.Paste")
			(net "Net_1464")
		)
		(pad "AG1" smd circle
			(at -22.800056 1.89992)
			(size 0.4572 0.4572)
			(layers "F.Cu" "F.Mask" "F.Paste")
			(net "Net_5406")
		)
		(pad "AG2" smd circle
			(at -21.850096 1.89992)
			(size 0.4572 0.4572)
			(layers "F.Cu" "F.Mask" "F.Paste")
			(net "Net_5407")
		)
		(pad "AG3" smd circle
			(at -20.899882 1.89992)
			(size 0.4572 0.4572)
			(layers "F.Cu" "F.Mask" "F.Paste")
			(net "GND")
		)
		(pad "AG4" smd circle
			(at -19.949922 1.89992)
			(size 0.4572 0.4572)
			(layers "F.Cu" "F.Mask" "F.Paste")
			(net "GND")
		)
		(pad "AG5" smd circle
			(at -18.999962 1.89992)
			(size 0.4572 0.4572)
			(layers "F.Cu" "F.Mask" "F.Paste")
			(net "GND")
		)
		(pad "AG6" smd circle
			(at -18.050002 1.89992)
			(size 0.4572 0.4572)
			(layers "F.Cu" "F.Mask" "F.Paste")
			(net "GND")
		)
		(pad "AG7" smd circle
			(at -17.100042 1.89992)
			(size 0.4572 0.4572)
			(layers "F.Cu" "F.Mask" "F.Paste")
			(net "SPI_PEX3_RST_N")
		)
		(pad "AG8" smd circle
			(at -16.150082 1.89992)
			(size 0.4572 0.4572)
			(layers "F.Cu" "F.Mask" "F.Paste")
			(net "SPI_PEX3_SDIO2")
		)
		(pad "AG9" smd circle
			(at -15.200122 1.89992)
			(size 0.4572 0.4572)
			(layers "F.Cu" "F.Mask" "F.Paste")
			(net "GND")
		)
		(pad "AG10" smd circle
			(at -14.249908 1.89992)
			(size 0.4572 0.4572)
			(layers "F.Cu" "F.Mask" "F.Paste")
			(net "GND")
		)
		(pad "AG11" smd circle
			(at -13.299948 1.89992)
			(size 0.4572 0.4572)
			(layers "F.Cu" "F.Mask" "F.Paste")
			(net "GND")
		)
		(pad "AG12" smd circle
			(at -12.349988 1.89992)
			(size 0.4572 0.4572)
			(layers "F.Cu" "F.Mask" "F.Paste")
			(net "GND")
		)
		(pad "AG13" smd circle
			(at -11.400028 1.89992)
			(size 0.4572 0.4572)
			(layers "F.Cu" "F.Mask" "F.Paste")
			(net "PCEPLL5_VDDA18_PEX3")
		)
		(pad "AG14" smd circle
			(at -10.450068 1.89992)
			(size 0.4572 0.4572)
			(layers "F.Cu" "F.Mask" "F.Paste")
			(net "GND")
		)
	)
)
